FILE_TYPE = MACRO_DRAWING;
SET COLOR_WIRE YELLOW;
SET COLOR_PROP ORANGE;
SET COLOR_DOT WHITE;
SET COLOR_ARC YELLOW;
SET COLOR_BODY GREEN;
SET COLOR_NOTE PURPLE;
SET PROP_DISPLAY VALUE;
SET PAGE_NUMBER P210;
FORCEADD QUANTA_TITLE_BLOCK_C..1
(0 0);
FORCEPROP 1 LAST CUSTOM_TXT_CDS <NAME_2>
J 0
(-3175 50);
FORCEPROP 1 LAST CUSTOM_TXT_CDS <NAME_1>
J 0
(-3175 175);
FORCEPROP 1 LAST CUSTOM_TXT_CDS <Q_NUMBER>
J 0
(-1403 103);
DISPLAY 1.212766 (-1403 103);
FORCEPROP 1 LAST CUSTOM_TXT_CDS <Q_PROJ>
J 0
(-2382 102);
DISPLAY 1.212766 (-2382 102);
FORCEPROP 1 LAST CUSTOM_TXT_CDS <Q_REV>
J 0
(-184 103);
DISPLAY 1.212766 (-184 103);
FORCEPROP 1 LAST CUSTOM_TXT_CDS <CON_LAST_MODIFIED>
J 0
(-1885 15);
DISPLAY 0.978723 (-1885 15);
FORCEPROP 1 LAST CUSTOM_TXT_CDS <CON_PAGE_NUM> OF <CON_TOTAL_PAGES>
J 0
(-446 18);
DISPLAY 0.978723 (-446 18);
FORCEPROP 1 LAST Q_DEPT BU9
J 1
(-3763 49);
DISPLAY 1.957447 (-3763 49);
PAINT GREEN (-3763 49);
FORCEPROP 1 LAST Q_TITLE eFUSE - M2
J 0
(-9300 50);
DISPLAY 2.446809 (-9300 50);
PAINT GREEN (-9300 50);
FORCEPROP 1 LAST COMMENT_BODY TRUE
J 0
(12 -13);
DISPLAY 0.978723 (12 -13);
PAINT GREEN (12 -13);
DISPLAY INVISIBLE (12 -13);
FORCEPROP 2 LAST PAGE_BORDER TRUE
J 0
(-7890 5250);
DISPLAY 0.638298 (-7890 5250);
PAINT PINK (-7890 5250);
DISPLAY INVISIBLE (-7890 5250);
FORCEPROP 1 LAST CDS_LMAN_SYM_OUTLINE -9475,6775,100,-125
J 0
(0 0);
DISPLAY 0.468085 (0 0);
PAINT GREEN (0 0);
DISPLAY INVISIBLE (0 0);
FORCEPROP 2 LAST CDS_LIB pure_quanta
J 0
(0 0);
DISPLAY INVISIBLE (0 0);
FORCEPROP 2 LAST CDS_XR_PAGE_TITLE CR-211 : @T6G_MB_LIB.T6G(SCH_1):PAGE211
J 0
(-7890 5250);
DISPLAY 0.638298 (-7890 5250);
PAINT PINK (-7890 5250);
DISPLAY INVISIBLE (-7890 5250);
FORCEPROP 2 LAST CUSTOM_TXT_CDS <XR_PAGE_TITLE>
J 0
(-7890 5250);
DISPLAY 0.638298 (-7890 5250);
PAINT PINK (-7890 5250);
DISPLAY INVISIBLE (-7890 5250);
FORCEPROP 0 LAST CDS_CON_LAST_MODIFIED Wed Mar 09 21:46:57 2022
J 0
(-1885 15);
DISPLAY INVISIBLE (-1885 15);
QUIT
